# T6G (Grand Teton) — schematic netlist excerpt (pin names and nets, part order shuffled) for the footprints in the layout excerpt that follows; sources: Cadence DE-HDL packaged netlist, KiCad conversion of 04192023_DAF0TMB3IC0_F0TG_MB_C_brd_V02_OCP.brd

J23  SCONN288_DDR506112002KQ  IO  pkg DDR288S_1-1VXC  page 91
  VIN_BULK0  = P12V_MEM_CPU0
  RFU0  = NC
  VIN_MGMT  = P3V3_AUX
  HSCL  = I3C_SPD_DDRF_CPU0_SCL
  HSDA  = I3C_SPD_DDRF_CPU0_SDA
  VSS0  = GND
  DQ0_A  = M_F_CPU0_SA_DQ<0>
  VSS1  = GND
  DQ1_A  = M_F_CPU0_SA_DQ<1>
  VSS2  = GND
  DQS0_A_T  = M_F_CPU0_SA_DQS_DP<0>
  DQS0_A_C  = M_F_CPU0_SA_DQS_DN<0>
  VSS3  = GND
  DQ4_A  = M_F_CPU0_SA_DQ<4>
  VSS4  = GND
  DQ5_A  = M_F_CPU0_SA_DQ<5>
  VSS5  = GND
  DQ8_A  = M_F_CPU0_SA_DQ<8>
  VSS6  = GND
  DQ9_A  = M_F_CPU0_SA_DQ<9>
  VSS7  = GND
  DQS1_A_T  = M_F_CPU0_SA_DQS_DP<1>
  DQS1_A_C  = M_F_CPU0_SA_DQS_DN<1>
  VSS8  = GND
  DQ12_A  = M_F_CPU0_SA_DQ<12>
  VSS9  = GND
  DQ13_A  = M_F_CPU0_SA_DQ<13>
  VSS10  = GND
  DQ16_A  = M_F_CPU0_SA_DQ<16>
  VSS11  = GND
  DQ17_A  = M_F_CPU0_SA_DQ<17>
  VSS12  = GND
  DQS2_A_T  = M_F_CPU0_SA_DQS_DP<2>
  DQS2_A_C  = M_F_CPU0_SA_DQS_DN<2>
  VSS13  = GND
  DQ20_A  = M_F_CPU0_SA_DQ<20>
  VSS14  = GND
  DQ21_A  = M_F_CPU0_SA_DQ<21>
  VSS15  = GND
  DQ24_A  = M_F_CPU0_SA_DQ<24>
  VSS16  = GND
  DQ25_A  = M_F_CPU0_SA_DQ<25>
  VSS17  = GND
  DQS3_A_T  = M_F_CPU0_SA_DQS_DP<3>
  DQS3_A_C  = M_F_CPU0_SA_DQS_DN<3>
  VSS18  = GND
  DQ28_A  = M_F_CPU0_SA_DQ<28>
  VSS19  = GND
  DQ29_A  = M_F_CPU0_SA_DQ<29>
  VSS20  = GND
  CB0_A  = M_F_CPU0_SA_CB<0>
  VSS21  = GND
  CB1_A  = M_F_CPU0_SA_CB<1>
  VSS22  = GND
  DQS4_A_T  = M_F_CPU0_SA_DQS_DP<4>
  DQS4_A_C  = M_F_CPU0_SA_DQS_DN<4>
  VSS23  = GND
  CB4_A  = M_F_CPU0_SA_CB<4>
  VSS24  = GND
  CB5_A  = M_F_CPU0_SA_CB<5>
  VSS25  = GND
  ALERT_N  = M_F_CPU0_ALERT_N
  VSS26  = GND
  CS0_A_N  = M_F_CPU0_SA_CS_N<0>
  VSS27  = GND
  CA0_A  = M_F_CPU0_SA_CA<0>
  VSS28  = GND
  CA2_A  = M_F_CPU0_SA_CA<2>
  VSS29  = GND
  CA4_A  = M_F_CPU0_SA_CA<4>
  VSS30  = GND
  CA6_A  = M_F_CPU0_SA_CA<6>
  VSS31  = GND
  PAR_A  = M_F_CPU0_SA_PAR
  VSS32  = GND
  CA0_B  = M_F_CPU0_SB_CA<0>
  VSS33  = GND
  CA2_B  = M_F_CPU0_SB_CA<2>
  VSS34  = GND
  CA4_B  = M_F_CPU0_SB_CA<4>
  VSS35  = GND
  CA6_B  = M_F_CPU0_SB_CA<6>
  VSS36  = GND
  CS0_B_N  = M_F_CPU0_SB_CS_N<0>
  VSS37  = GND
  \lbd||rsp_a_n\  = M_F_CPU0_SA_RSP<0>
  \lbs||rsp_b_n\  = M_F_CPU0_SB_RSP<0>
  VSS38  = GND
  CB4_B  = M_F_CPU0_SB_CB<4>
  VSS39  = GND
  CB5_B  = M_F_CPU0_SB_CB<5>
  VSS40  = GND
  \dqs9_b_t||tdqs9_b_t||dbi4_b_n\  = M_F_CPU0_SB_DQS_DP<9>
  \dqs9_b_c||tdqs9_b_c\  = M_F_CPU0_SB_DQS_DN<9>
  VSS41  = GND
  CB0_B  = M_F_CPU0_SB_CB<0>
  VSS42  = GND
  CB1_B  = M_F_CPU0_SB_CB<1>
  VSS43  = GND
  DQ0_B  = M_F_CPU0_SB_DQ<0>
  VSS44  = GND
  DQ1_B  = M_F_CPU0_SB_DQ<1>
  VSS45  = GND
  DQS0_B_T  = M_F_CPU0_SB_DQS_DP<0>
  DQS0_B_C  = M_F_CPU0_SB_DQS_DN<0>
  VSS46  = GND
  DQ4_B  = M_F_CPU0_SB_DQ<4>
  VSS47  = GND
  DQ5_B  = M_F_CPU0_SB_DQ<5>
  VSS48  = GND
  DQ8_B  = M_F_CPU0_SB_DQ<8>
  VSS49  = GND
  DQ9_B  = M_F_CPU0_SB_DQ<9>
  VSS50  = GND
  DQS1_B_T  = M_F_CPU0_SB_DQS_DP<1>
  DQS1_B_C  = M_F_CPU0_SB_DQS_DN<1>
  VSS51  = GND
  DQ12_B  = M_F_CPU0_SB_DQ<12>
  VSS52  = GND
  DQ13_B  = M_F_CPU0_SB_DQ<13>
  VSS53  = GND
  DQ16_B  = M_F_CPU0_SB_DQ<16>
  VSS54  = GND
  DQ17_B  = M_F_CPU0_SB_DQ<17>
  VSS55  = GND
  DQS2_B_T  = M_F_CPU0_SB_DQS_DP<2>
  DQS2_B_C  = M_F_CPU0_SB_DQS_DN<2>
  VSS56  = GND
  DQ20_B  = M_F_CPU0_SB_DQ<20>
  VSS57  = GND
  DQ21_B  = M_F_CPU0_SB_DQ<21>
  VSS58  = GND
  DQ24_B  = M_F_CPU0_SB_DQ<24>
  VSS59  = GND
  DQ25_B  = M_F_CPU0_SB_DQ<25>
  VSS60  = GND
  DQS3_B_T  = M_F_CPU0_SB_DQS_DP<3>
  DQS3_B_C  = M_F_CPU0_SB_DQS_DN<3>
  VSS61  = GND
  DQ28_B  = M_F_CPU0_SB_DQ<28>
  VSS62  = GND
  DQ29_B  = M_F_CPU0_SB_DQ<29>
  VSS63  = GND
  RFU1  = NC
  VIN_BULK1  = P12V_MEM_CPU0
  VIN_BULK2  = P12V_MEM_CPU0
  \pwr_good||fail_n\  = PWRGD_CHF_CPU0_DIMM
  HAS  = PD_CHF_CPU0_DIMM_SAA
  RFU2  = NC
  RFU3  = NC
  VSS64  = GND
  DQ2_A  = M_F_CPU0_SA_DQ<2>
  VSS65  = GND
  DQ3_A  = M_F_CPU0_SA_DQ<3>
  VSS66  = GND
  \dqs5_a_c||tdqs5_a_c||dqs5_a_t||tdqs5_a_t\  = M_F_CPU0_SA_DQS_DN<5>
  \dqs5_a_t||tdqs5_a_t\  = M_F_CPU0_SA_DQS_DP<5>
  VSS67  = GND
  DQ6_A  = M_F_CPU0_SA_DQ<6>
  VSS68  = GND
  DQ7_A  = M_F_CPU0_SA_DQ<7>
  VSS69  = GND
  DQ10_A  = M_F_CPU0_SA_DQ<10>
  VSS70  = GND
  DQ11_A  = M_F_CPU0_SA_DQ<11>
  VSS71  = GND
  \dqs6_a_c||tdqs6_a_c||dqs6_a_t||tdqs6_a_t\  = M_F_CPU0_SA_DQS_DN<6>
  \dqs6_a_t||tdqs6_a_t\  = M_F_CPU0_SA_DQS_DP<6>
  VSS72  = GND
  DQ14_A  = M_F_CPU0_SA_DQ<14>
  VSS73  = GND
  DQ15_A  = M_F_CPU0_SA_DQ<15>
  VSS74  = GND
  DQ18_A  = M_F_CPU0_SA_DQ<18>
  VSS75  = GND
  DQ19_A  = M_F_CPU0_SA_DQ<19>
  VSS76  = GND
  \dqs7_a_c||tdqs7_a_c\  = M_F_CPU0_SA_DQS_DN<7>
  \dqs7_a_t||tdqs7_a_t\  = M_F_CPU0_SA_DQS_DP<7>
  VSS77  = GND
  DQ22_A  = M_F_CPU0_SA_DQ<22>
  VSS78  = GND
  DQ23_A  = M_F_CPU0_SA_DQ<23>
  VSS79  = GND
  DQ26_A  = M_F_CPU0_SA_DQ<26>
  VSS80  = GND
  DQ27_A  = M_F_CPU0_SA_DQ<27>
  VSS81  = GND
  \dqs8_a_c||tdqs8_a_c\  = M_F_CPU0_SA_DQS_DN<8>
  \dqs8_a_t||tdqs8_a_t\  = M_F_CPU0_SA_DQS_DP<8>
  VSS82  = GND
  DQ30_A  = M_F_CPU0_SA_DQ<30>
  VSS83  = GND
  DQ31_A  = M_F_CPU0_SA_DQ<31>
  VSS84  = GND
  CB2_A  = M_F_CPU0_SA_CB<2>
  VSS85  = GND
  CB3_A  = M_F_CPU0_SA_CB<3>
  VSS86  = GND
  \dqs9_a_c||tdqs9_a_c\  = M_F_CPU0_SA_DQS_DN<9>
  \dqs9_a_t||tdqs9_a_t\  = M_F_CPU0_SA_DQS_DP<9>
  VSS87  = GND
  CB6_A  = M_F_CPU0_SA_CB<6>
  VSS88  = GND
  CB7_A  = M_F_CPU0_SA_CB<7>
  VSS89  = GND
  RESET_N  = M_F_CPU0_RESET_N
  VSS90  = GND
  CS1_A_N  = M_F_CPU0_SA_CS_N<1>
  VSS91  = GND
  CA1_A  = M_F_CPU0_SA_CA<1>
  VSS92  = GND
  CA3_A  = M_F_CPU0_SA_CA<3>
  VSS93  = GND
  CA5_A  = M_F_CPU0_SA_CA<5>
  VSS94  = GND
  CK_T  = M_F_CPU0_CLK_DP<0>
  CK_C  = M_F_CPU0_CLK_DN<0>
  VSS95  = GND
  RFU4  = NC
  CA1_B  = M_F_CPU0_SB_CA<1>
  VSS96  = GND
  CA3_B  = M_F_CPU0_SB_CA<3>
  VSS97  = GND
  CA5_B  = M_F_CPU0_SB_CA<5>
  VSS98  = GND
  PAR_B  = M_F_CPU0_SB_PAR
  VSS99  = GND
  CS1_B_N  = M_F_CPU0_SB_CS_N<1>
  VSS100  = GND
  RFU5  = NC
  RFU6  = NC
  VSS101  = GND
  CB6_B  = M_F_CPU0_SB_CB<6>
  VSS102  = GND
  CB7_B  = M_F_CPU0_SB_CB<7>
  VSS103  = GND
  DQS4_B_C  = M_F_CPU0_SB_DQS_DN<4>
  DQS4_B_T  = M_F_CPU0_SB_DQS_DP<4>
  VSS104  = GND
  CB2_B  = M_F_CPU0_SB_CB<2>
  VSS105  = GND
  CB3_B  = M_F_CPU0_SB_CB<3>
  VSS106  = GND
  DQ2_B  = M_F_CPU0_SB_DQ<2>
  VSS107  = GND
  DQ3_B  = M_F_CPU0_SB_DQ<3>
  VSS108  = GND
  \dqs5_b_c||tdqs5_b_c\  = M_F_CPU0_SB_DQS_DN<5>
  \dqs5_b_t||tdqs5_b_t\  = M_F_CPU0_SB_DQS_DP<5>
  VSS109  = GND
  DQ6_B  = M_F_CPU0_SB_DQ<6>
  VSS110  = GND
  DQ7_B  = M_F_CPU0_SB_DQ<7>
  VSS111  = GND
  DQ10_B  = M_F_CPU0_SB_DQ<10>
  VSS112  = GND
  DQ11_B  = M_F_CPU0_SB_DQ<11>
  VSS113  = GND
  \dqs6_b_c||tdqs6_b_c\  = M_F_CPU0_SB_DQS_DN<6>
  \dqs6_b_t||tdqs6_b_t\  = M_F_CPU0_SB_DQS_DP<6>
  VSS114  = GND
  DQ14_B  = M_F_CPU0_SB_DQ<14>
  VSS115  = GND
  DQ15_B  = M_F_CPU0_SB_DQ<15>
  VSS116  = GND
  DQ18_B  = M_F_CPU0_SB_DQ<18>
  VSS117  = GND
  DQ19_B  = M_F_CPU0_SB_DQ<19>
  VSS118  = GND
  \dqs7_b_c||tdqs7_b_c\  = M_F_CPU0_SB_DQS_DN<7>
  \dqs7_b_t||tdqs7_b_t\  = M_F_CPU0_SB_DQS_DP<7>
  VSS119  = GND
  DQ22_B  = M_F_CPU0_SB_DQ<22>
  VSS120  = GND
  DQ23_B  = M_F_CPU0_SB_DQ<23>
  VSS121  = GND
  DQ26_B  = M_F_CPU0_SB_DQ<26>
  VSS122  = GND
  DQ27_B  = M_F_CPU0_SB_DQ<27>
  VSS123  = GND
  \dqs8_b_c||tdqs8_b_c\  = M_F_CPU0_SB_DQS_DN<8>
  \dqs8_b_t||tdqs8_b_t\  = M_F_CPU0_SB_DQS_DP<8>
  VSS124  = GND
  DQ30_B  = M_F_CPU0_SB_DQ<30>
  VSS125  = GND
  DQ31_B  = M_F_CPU0_SB_DQ<31>
  VSS126  = GND
  G1  = GND
  G2  = GND
  G3  = GND

(kicad_pcb
	(version 20260206)
	(generator "pcbnew")
	(generator_version "10.0")
	(general
		(thickness 1.6)
		(legacy_teardrops no)
	)
	(paper "A4")
	(title_block
		(title "04192023_DAF0TMB3IC0_F0TG_MB_C_brd_V02_OCP.brd")
		(comment 1 "Grand Teton / footprint 2449 of 8354 (J23), pads 47-92 of 291")
	)
	(layers
		(0 "F.Cu" signal "TOP")
		(4 "In1.Cu" signal "GND")
		(6 "In2.Cu" signal "IN1")
		(8 "In3.Cu" signal "GND1")
		(10 "In4.Cu" signal "IN2")
		(12 "In5.Cu" signal "GND2")
		(14 "In6.Cu" signal "IN3")
		(16 "In7.Cu" signal "GND3")
		(18 "In8.Cu" signal "VCC")
		(20 "In9.Cu" signal "VCC1")
		(22 "In10.Cu" signal "GND4")
		(24 "In11.Cu" signal "IN4")
		(26 "In12.Cu" signal "GND5")
		(28 "In13.Cu" signal "IN5")
		(30 "In14.Cu" signal "GND6")
		(32 "In15.Cu" signal "IN6")
		(34 "In16.Cu" signal "GND7")
		(2 "B.Cu" signal "BOTTOM")
		(9 "F.Adhes" user "F.Adhesive")
		(11 "B.Adhes" user "B.Adhesive")
		(13 "F.Paste" user "Package Geometry/Pastemask Top")
		(15 "B.Paste" user "Package Geometry/Pastemask Bottom")
		(5 "F.SilkS" user "Ref Des/Silkscreen Top")
		(7 "B.SilkS" user "Ref Des/Silkscreen Bottom")
		(1 "F.Mask" user "Board Geometry/Soldermask Top")
		(3 "B.Mask" user "Board Geometry/Soldermask Bottom")
		(17 "Dwgs.User" user "User.Drawings")
		(19 "Cmts.User" user "User.Comments")
		(21 "Eco1.User" user "User.Eco1")
		(23 "Eco2.User" user "User.Eco2")
		(25 "Edge.Cuts" user "Board Geometry/Outline")
		(27 "Margin" user)
		(31 "F.CrtYd" user "Package Geometry/Place Bound Top")
		(29 "B.CrtYd" user "Package Geometry/Place Bound Bottom")
		(35 "F.Fab" user "Ref Des/Assembly Top")
		(33 "B.Fab" user "Ref Des/Assembly Bottom")
	)
	(footprint ""
		(layer "F.Cu")
		(at 267.598144 -255.560068 180)
		(property "Reference" "J23"
			(at -2.2098 -81.984088 0)
			(unlocked yes)
			(layer "F.SilkS")
			(effects
				(font
					(size 0.7874 0.5842)
					(thickness 0.1524)
				)
			)
		)
		(property "Value" ""
			(at 0 0 180)
			(layer "F.Fab")
			(effects
				(font
					(size 1.27 1.27)
				)
			)
		)
		(duplicate_pad_numbers_are_jumpers no)
		(pad "47" smd rect
			(at -2.050034 -24.224996 90)
			(size 0.519938 1.4986)
			(layers "F.Cu" "F.Mask" "F.Paste")
			(net "M_F_CPU0_SA_DQ<28>")
		)
		(pad "48" smd rect
			(at -2.050034 -23.375112 90)
			(size 0.519938 1.4986)
			(layers "F.Cu" "F.Mask" "F.Paste")
			(net "GND")
		)
		(pad "49" smd rect
			(at -2.050034 -22.524974 90)
			(size 0.519938 1.4986)
			(layers "F.Cu" "F.Mask" "F.Paste")
			(net "M_F_CPU0_SA_DQ<29>")
		)
		(pad "50" smd rect
			(at -2.050034 -21.67509 90)
			(size 0.519938 1.4986)
			(layers "F.Cu" "F.Mask" "F.Paste")
			(net "GND")
		)
		(pad "51" smd rect
			(at -2.050034 -20.824952 90)
			(size 0.519938 1.4986)
			(layers "F.Cu" "F.Mask" "F.Paste")
			(net "M_F_CPU0_SA_CB<0>")
		)
		(pad "52" smd rect
			(at -2.050034 -19.975068 90)
			(size 0.519938 1.4986)
			(layers "F.Cu" "F.Mask" "F.Paste")
			(net "GND")
		)
		(pad "53" smd rect
			(at -2.050034 -19.12493 90)
			(size 0.519938 1.4986)
			(layers "F.Cu" "F.Mask" "F.Paste")
			(net "M_F_CPU0_SA_CB<1>")
		)
		(pad "54" smd rect
			(at -2.050034 -18.275046 90)
			(size 0.519938 1.4986)
			(layers "F.Cu" "F.Mask" "F.Paste")
			(net "GND")
		)
		(pad "55" smd rect
			(at -2.050034 -17.424908 90)
			(size 0.519938 1.4986)
			(layers "F.Cu" "F.Mask" "F.Paste")
			(net "M_F_CPU0_SA_DQS_DP<4>")
		)
		(pad "56" smd rect
			(at -2.050034 -16.575024 90)
			(size 0.519938 1.4986)
			(layers "F.Cu" "F.Mask" "F.Paste")
			(net "M_F_CPU0_SA_DQS_DN<4>")
		)
		(pad "57" smd rect
			(at -2.050034 -15.724886 90)
			(size 0.519938 1.4986)
			(layers "F.Cu" "F.Mask" "F.Paste")
			(net "GND")
		)
		(pad "58" smd rect
			(at -2.050034 -14.875002 90)
			(size 0.519938 1.4986)
			(layers "F.Cu" "F.Mask" "F.Paste")
			(net "M_F_CPU0_SA_CB<4>")
		)
		(pad "59" smd rect
			(at -2.050034 -14.025118 90)
			(size 0.519938 1.4986)
			(layers "F.Cu" "F.Mask" "F.Paste")
			(net "GND")
		)
		(pad "60" smd rect
			(at -2.050034 -13.17498 90)
			(size 0.519938 1.4986)
			(layers "F.Cu" "F.Mask" "F.Paste")
			(net "M_F_CPU0_SA_CB<5>")
		)
		(pad "61" smd rect
			(at -2.050034 -12.325096 90)
			(size 0.519938 1.4986)
			(layers "F.Cu" "F.Mask" "F.Paste")
			(net "GND")
		)
		(pad "62" smd rect
			(at -2.050034 -11.474958 90)
			(size 0.519938 1.4986)
			(layers "F.Cu" "F.Mask" "F.Paste")
			(net "M_F_CPU0_ALERT_N")
		)
		(pad "63" smd rect
			(at -2.050034 -10.625074 90)
			(size 0.519938 1.4986)
			(layers "F.Cu" "F.Mask" "F.Paste")
			(net "GND")
		)
		(pad "64" smd rect
			(at -2.050034 -9.774936 90)
			(size 0.519938 1.4986)
			(layers "F.Cu" "F.Mask" "F.Paste")
			(net "M_F_CPU0_SA_CS_N<0>")
		)
		(pad "65" smd rect
			(at -2.050034 -8.925052 90)
			(size 0.519938 1.4986)
			(layers "F.Cu" "F.Mask" "F.Paste")
			(net "GND")
		)
		(pad "66" smd rect
			(at -2.050034 -8.074914 90)
			(size 0.519938 1.4986)
			(layers "F.Cu" "F.Mask" "F.Paste")
			(net "M_F_CPU0_SA_CA<0>")
		)
		(pad "67" smd rect
			(at -2.050034 -7.22503 90)
			(size 0.519938 1.4986)
			(layers "F.Cu" "F.Mask" "F.Paste")
			(net "GND")
		)
		(pad "68" smd rect
			(at -2.050034 -6.374892 90)
			(size 0.519938 1.4986)
			(layers "F.Cu" "F.Mask" "F.Paste")
			(net "M_F_CPU0_SA_CA<2>")
		)
		(pad "69" smd rect
			(at -2.050034 -5.525008 90)
			(size 0.519938 1.4986)
			(layers "F.Cu" "F.Mask" "F.Paste")
			(net "GND")
		)
		(pad "70" smd rect
			(at -2.050034 -4.675124 90)
			(size 0.519938 1.4986)
			(layers "F.Cu" "F.Mask" "F.Paste")
			(net "M_F_CPU0_SA_CA<4>")
		)
		(pad "71" smd rect
			(at -2.050034 -3.824986 90)
			(size 0.519938 1.4986)
			(layers "F.Cu" "F.Mask" "F.Paste")
			(net "GND")
		)
		(pad "72" smd rect
			(at -2.050034 -2.975102 90)
			(size 0.519938 1.4986)
			(layers "F.Cu" "F.Mask" "F.Paste")
			(net "M_F_CPU0_SA_CA<6>")
		)
		(pad "73" smd rect
			(at -2.050034 -2.124964 90)
			(size 0.519938 1.4986)
			(layers "F.Cu" "F.Mask" "F.Paste")
			(net "GND")
		)
		(pad "74" smd rect
			(at -2.050034 -1.27508 90)
			(size 0.519938 1.4986)
			(layers "F.Cu" "F.Mask" "F.Paste")
			(net "M_F_CPU0_SA_PAR")
		)
		(pad "75" smd rect
			(at -2.050034 -0.424942 90)
			(size 0.519938 1.4986)
			(layers "F.Cu" "F.Mask" "F.Paste")
			(net "GND")
		)
		(pad "76" smd rect
			(at -2.050034 5.525008 90)
			(size 0.519938 1.4986)
			(layers "F.Cu" "F.Mask" "F.Paste")
			(net "M_F_CPU0_SB_CA<0>")
		)
		(pad "77" smd rect
			(at -2.050034 6.374892 90)
			(size 0.519938 1.4986)
			(layers "F.Cu" "F.Mask" "F.Paste")
			(net "GND")
		)
		(pad "78" smd rect
			(at -2.050034 7.22503 90)
			(size 0.519938 1.4986)
			(layers "F.Cu" "F.Mask" "F.Paste")
			(net "M_F_CPU0_SB_CA<2>")
		)
		(pad "79" smd rect
			(at -2.050034 8.074914 90)
			(size 0.519938 1.4986)
			(layers "F.Cu" "F.Mask" "F.Paste")
			(net "GND")
		)
		(pad "80" smd rect
			(at -2.050034 8.925052 90)
			(size 0.519938 1.4986)
			(layers "F.Cu" "F.Mask" "F.Paste")
			(net "M_F_CPU0_SB_CA<4>")
		)
		(pad "81" smd rect
			(at -2.050034 9.774936 90)
			(size 0.519938 1.4986)
			(layers "F.Cu" "F.Mask" "F.Paste")
			(net "GND")
		)
		(pad "82" smd rect
			(at -2.050034 10.625074 90)
			(size 0.519938 1.4986)
			(layers "F.Cu" "F.Mask" "F.Paste")
			(net "M_F_CPU0_SB_CA<6>")
		)
		(pad "83" smd rect
			(at -2.050034 11.474958 90)
			(size 0.519938 1.4986)
			(layers "F.Cu" "F.Mask" "F.Paste")
			(net "GND")
		)
		(pad "84" smd rect
			(at -2.050034 12.325096 90)
			(size 0.519938 1.4986)
			(layers "F.Cu" "F.Mask" "F.Paste")
			(net "M_F_CPU0_SB_CS_N<0>")
		)
		(pad "85" smd rect
			(at -2.050034 13.17498 90)
			(size 0.519938 1.4986)
			(layers "F.Cu" "F.Mask" "F.Paste")
			(net "GND")
		)
		(pad "86" smd rect
			(at -2.050034 14.025118 90)
			(size 0.519938 1.4986)
			(layers "F.Cu" "F.Mask" "F.Paste")
			(net "M_F_CPU0_SA_RSP<0>")
		)
		(pad "87" smd rect
			(at -2.050034 14.875002 90)
			(size 0.519938 1.4986)
			(layers "F.Cu" "F.Mask" "F.Paste")
			(net "M_F_CPU0_SB_RSP<0>")
		)
		(pad "88" smd rect
			(at -2.050034 15.724886 90)
			(size 0.519938 1.4986)
			(layers "F.Cu" "F.Mask" "F.Paste")
			(net "GND")
		)
		(pad "89" smd rect
			(at -2.050034 16.575024 90)
			(size 0.519938 1.4986)
			(layers "F.Cu" "F.Mask" "F.Paste")
			(net "M_F_CPU0_SB_CB<4>")
		)
		(pad "90" smd rect
			(at -2.050034 17.424908 90)
			(size 0.519938 1.4986)
			(layers "F.Cu" "F.Mask" "F.Paste")
			(net "GND")
		)
		(pad "91" smd rect
			(at -2.050034 18.275046 90)
			(size 0.519938 1.4986)
			(layers "F.Cu" "F.Mask" "F.Paste")
			(net "M_F_CPU0_SB_CB<5>")
		)
		(pad "92" smd rect
			(at -2.050034 19.12493 90)
			(size 0.519938 1.4986)
			(layers "F.Cu" "F.Mask" "F.Paste")
			(net "GND")
		)
	)
)
